FILE_TYPE = CONNECTIVITY;
{Allegro Design Entry HDL 17.4-2019 S026 (4007227) 1/17/2022}
"PAGE_NUMBER" = 361;
0"NC";
1"GND\g";
2"GND\g";
3"GND\g";
4"GND\g";
5"GND\g";
6"GND\g";
7"GND\g";
8"GND\g";
9"GND\g";
10"GND\g";
11"P3V3_AUX\g";
12"CPU_FRU_ADDR1"CDS_PHYS_NET_NAME"PCA9548_PCIE_ADDR2";
13"P3V3_AUX\g";
14"P3V3_AUX\g";
15"GND\g";
16"P3V3_AUX\g"$PHYS_NET_NAME"P3V3_AUX"CDS_PHYS_NET_NAME"P3V3_AUX"VOLTAGE"3.3"$PHYS_NET_NAME"P3V3_AUX"CDS_PHYS_NET_NAME"P3V3_AUX"VOLTAGE"3.3"$PHYS_NET_NAME"P3V3_AUX"CDS_PHYS_NET_NAME"P3V3_AUX"VOLTAGE"3.3";
17"P3V3_AUX\g";
18"P3V3_AUX\g"$PHYS_NET_NAME"P3V3_AUX"CDS_PHYS_NET_NAME"P3V3_AUX"VOLTAGE"3.3"$PHYS_NET_NAME"P3V3_AUX"CDS_PHYS_NET_NAME"P3V3_AUX"VOLTAGE"3.3"$PHYS_NET_NAME"P3V3_AUX"CDS_PHYS_NET_NAME"P3V3_AUX"VOLTAGE"3.3";
19"GND\g";
20"CPU_FRU_ADDR0"CDS_PHYS_NET_NAME"PCA9548_PCIE_ADDR2";
21"PD_MB_FRU_WP";
22"SMB_FRU_3V3AUX_R1_SDA"CDS_PHYS_NET_NAME"SMB_PCIE_3V3AUX_SDA_R"CDS_PHYS_NET_NAME"SMB_PCIE_3V3AUX_SCL";
23"MB_FRU_ADDR0"CDS_PHYS_NET_NAME"PCA9548_PCIE_ADDR2";
24"MB_FRU_ADDR2"CDS_PHYS_NET_NAME"PCA9548_PCIE_ADDR2";
25"MB_FRU_ADDR1"CDS_PHYS_NET_NAME"PCA9548_PCIE_ADDR2";
26"SMB_FRU_3V3AUX_R1_SCL"CDS_PHYS_NET_NAME"SMB_PCIE_3V3AUX_SCL_R"CDS_PHYS_NET_NAME"SMB_PCIE_3V3AUX_SDA";
27"SMB_CPU_FRU_3V3AUX_SDA"CDS_PHYS_NET_NAME"SMB_PCIE_3V3AUX_SDA_R"CDS_PHYS_NET_NAME"SMB_PCIE_3V3AUX_SCL";
28"CPU_FRU_ADDR2"CDS_PHYS_NET_NAME"PCA9548_PCIE_ADDR2";
29"SMB_CPU_FRU_3V3AUX_SCL"CDS_PHYS_NET_NAME"SMB_PCIE_3V3AUX_SCL_R"CDS_PHYS_NET_NAME"SMB_PCIE_3V3AUX_SDA";
30"SMB_FRU_3V3AUX_SCL";
31"PD_CPU_FRU_WP";
32"SMB_FRU_3V3AUX_SCL";
33"SMB_FRU_3V3AUX_SDA";
34"SMB_FRU_3V3AUX_SDA";
%"Q_RES"
"2","(1800,1375)","0","pure_quanta","I101";
;
LOCATION"R60"
$SEC"1"
CDS_SEC"1"
VALUE"10K"
TOLERANCE"1%"
WATTAGE"1/16W"
MATERIAL"EMPTY"
PACK_TYPE"0402LF"
CDS_LIB"pure_quanta"
PART_NUMBER"CS31002FB08";
"A"
$PN"1"13;
"B"
$PN"2"12;
%"UNIVERSAL_POWER"
"1","(1525,1750)","0","pure_quanta_power","I102";
;
HDL_POWER"P3V3_AUX"
CDS_LIB"pure_quanta_power";
"A"13;
%"Q_RES"
"2","(1525,1375)","0","pure_quanta","I103";
;
LOCATION"R52"
$SEC"1"
CDS_SEC"1"
WATTAGE"1/16W"
MATERIAL"EMPTY"
PACK_TYPE"0402LF"
TOLERANCE"1%"
VALUE"10K"
CDS_LIB"pure_quanta"
PART_NUMBER"CS31002FB08";
"A"
$PN"1"13;
"B"
$PN"2"28;
%"Q_RES"
"2","(1800,825)","0","pure_quanta","I104";
;
LOCATION"R62"
$SEC"1"
CDS_SEC"1"
VALUE"1K"
TOLERANCE"1%"
MATERIAL"CHIP"
PACK_TYPE"0402LF"
WATTAGE"1/16W"
CDS_LIB"pure_quanta"
PART_NUMBER"CS21002FB06";
"A"
$PN"1"12;
"B"
$PN"2"1;
%"UNIVERSAL_GND"
"1","(1800,600)","0","pure_quanta_power","I105";
;
ROOM"IO_SLOT"
CDS_LIB"pure_quanta_power"
HDL_POWER"GND";
"A"1;
%"UNIVERSAL_GND"
"1","(1525,600)","0","pure_quanta_power","I106";
;
ROOM"IO_SLOT"
CDS_LIB"pure_quanta_power"
HDL_POWER"GND";
"A"2;
%"Q_RES"
"2","(1525,825)","0","pure_quanta","I107";
;
LOCATION"R54"
$SEC"1"
CDS_SEC"1"
VALUE"1K"
MATERIAL"CHIP"
WATTAGE"1/16W"
PACK_TYPE"0402LF"
TOLERANCE"1%"
CDS_LIB"pure_quanta"
PART_NUMBER"CS21002FB06";
"A"
$PN"1"28;
"B"
$PN"2"2;
%"UNIVERSAL_GND"
"1","(225,750)","0","pure_quanta_power","I108";
;
CDS_LIB"pure_quanta_power"
HDL_POWER"GND";
"A"19;
%"UNIVERSAL_POWER"
"1","(-750,1725)","0","pure_quanta_power","I109";
;
HDL_POWER"P3V3_AUX"
CDS_LIB"pure_quanta_power";
"A"18;
%"Q_CAP"
"1","(-750,1400)","2","pure_quanta","I110";
;
LOCATION"C1"
$SEC"1"
CDS_SEC"1"
TOLERANCE"10%"
MATERIAL"X7R"
VOLTAGE"25V"
VALUE"0.1UF"
PACK_TYPE"0402"
CDS_LIB"pure_quanta"
PART_NUMBER"CH4104K1B00";
"B"
$PN"2"3;
"A"
$PN"1"18;
%"UNIVERSAL_GND"
"1","(-750,1175)","0","pure_quanta_power","I111";
;
CDS_LIB"pure_quanta_power"
HDL_POWER"GND";
"A"3;
%"UNIVERSAL_POWER"
"1","(-2000,1650)","0","pure_quanta_power","I112";
;
HDL_POWER"P3V3_AUX"
CDS_LIB"pure_quanta_power";
"A"17;
%"Q_RES"
"2","(-1900,1350)","0","pure_quanta","I113";
;
LOCATION"R24"
$SEC"1"
CDS_SEC"1"
MATERIAL"EMPTY"
WATTAGE"1/16W"
TOLERANCE"5%"
VALUE"4.7K"
PACK_TYPE"0402LF"
CDS_LIB"pure_quanta"
PART_NUMBER"CS24702JB10";
"A"
$PN"1"17;
"B"
$PN"2"27;
%"Q_RES"
"2","(-2000,1350)","2","pure_quanta","I114";
;
LOCATION"R4"
$SEC"1"
CDS_SEC"1"
VALUE"4.7K"
TOLERANCE"5%"
WATTAGE"1/16W"
MATERIAL"EMPTY"
PACK_TYPE"0402LF"
CDS_LIB"pure_quanta"
PART_NUMBER"CS24702JB10";
"A"
$PN"1"17;
"B"
$PN"2"29;
%"Q_RES"
"2","(-1075,750)","0","pure_quanta","I115";
;
LOCATION"R44"
$SEC"1"
CDS_SEC"1"
VALUE"1K"
PACK_TYPE"0402LF"
MATERIAL"CHIP"
WATTAGE"1/16W"
TOLERANCE"1%"
CDS_LIB"pure_quanta"
PART_NUMBER"CS21002FB06";
"A"
$PN"1"31;
"B"
$PN"2"4;
%"UNIVERSAL_GND"
"1","(-1075,525)","0","pure_quanta_power","I116";
;
CDS_LIB"pure_quanta_power"
HDL_POWER"GND";
"A"4;
%"Q_RES"
"2","(2075,1375)","0","pure_quanta","I120";
;
LOCATION"R68"
$SEC"1"
CDS_SEC"1"
VALUE"1K"
TOLERANCE"1%"
WATTAGE"1/16W"
MATERIAL"EMPTY"
PACK_TYPE"0402LF"
CDS_LIB"pure_quanta"
PART_NUMBER"CS21002FB06";
"A"
$PN"1"13;
"B"
$PN"2"20;
%"Q_RES"
"2","(2075,825)","0","pure_quanta","I121";
;
LOCATION"R69"
$SEC"1"
CDS_SEC"1"
VALUE"10K"
MATERIAL"CHIP"
PACK_TYPE"0402LF"
TOLERANCE"1%"
WATTAGE"1/16W"
CDS_LIB"pure_quanta"
PART_NUMBER"CS31002FB08";
"A"
$PN"1"20;
"B"
$PN"2"10;
%"Q_RES"
"1","(-2325,1050)","0","pure_quanta","I122";
;
LOCATION"R121"
$SEC"1"
CDS_SEC"1"
VALUE"0"
MATERIAL"CHIP"
TOLERANCE"5%"
CDS_LIB"pure_quanta"
WATTAGE"1/16W"
PACK_TYPE"0402LF"
PART_NUMBER"CS00002JB13";
"B"
$PN"2"29;
"A"
$PN"1"30;
%"Q_RES"
"1","(-2325,1000)","0","pure_quanta","I123";
;
LOCATION"R125"
$SEC"1"
CDS_SEC"1"
TOLERANCE"5%"
MATERIAL"CHIP"
VALUE"0"
PACK_TYPE"0402LF"
WATTAGE"1/16W"
CDS_LIB"pure_quanta"
PART_NUMBER"CS00002JB13";
"B"
$PN"2"27;
"A"
$PN"1"34;
%"Q_RES"
"1","(-2375,3350)","0","pure_quanta","I124";
;
LOCATION"R85"
$SEC"1"
CDS_SEC"1"
MATERIAL"CHIP"
TOLERANCE"5%"
VALUE"0"
WATTAGE"1/16W"
PACK_TYPE"0402LF"
CDS_LIB"pure_quanta"
PART_NUMBER"CS00002JB13";
"B"
$PN"2"26;
"A"
$PN"1"32;
%"Q_RES"
"1","(-2375,3300)","0","pure_quanta","I125";
;
LOCATION"R86"
$SEC"1"
CDS_SEC"1"
MATERIAL"CHIP"
TOLERANCE"5%"
VALUE"0"
WATTAGE"1/16W"
PACK_TYPE"0402LF"
CDS_LIB"pure_quanta"
PART_NUMBER"CS00002JB13";
"B"
$PN"2"22;
"A"
$PN"1"33;
%"M24128BWMN6TP"
"1","(-250,3375)","0","pure_quanta","I35";
;
LOCATION"U64"
$SEC"1"
CDS_SEC"1"
PART_TYPE"SMLF"
VALUE"M24128-BWMN6TP"
MATERIAL"IC"
CDS_LIB"pure_quanta"
NEEDS_NO_SIZE"TRUE"
CDS_LMAN_SYM_OUTLINE"-150,125,150,-125"
PART_NUMBER"AKE30Z00613";
"E0"
$PN"1"23;
"E1"
$PN"2"25;
"E2"
$PN"3"24;
"VSS"
$PN"4"15;
"SDA"
$PN"5"22;
"SCL"
$PN"6"26;
"WC# \B"
$PN"7"21;
"VCC"
$PN"8"16;
%"Q_RES"
"2","(1775,3675)","0","pure_quanta","I45";
;
LOCATION"R717"
$SEC"1"
CDS_SEC"1"
TOLERANCE"1%"
VALUE"10K"
WATTAGE"1/16W"
MATERIAL"EMPTY"
PACK_TYPE"0402LF"
CDS_LIB"pure_quanta"
PART_NUMBER"CS31002FB08";
"A"
$PN"1"14;
"B"
$PN"2"25;
%"Q_RES"
"2","(1500,3675)","0","pure_quanta","I47";
;
LOCATION"R713"
$SEC"1"
CDS_SEC"1"
MATERIAL"EMPTY"
TOLERANCE"1%"
VALUE"10K"
PACK_TYPE"0402LF"
WATTAGE"1/16W"
CDS_LIB"pure_quanta"
PART_NUMBER"CS31002FB08";
"A"
$PN"1"14;
"B"
$PN"2"24;
%"UNIVERSAL_GND"
"1","(2050,2900)","0","pure_quanta_power","I49";
;
CDS_LIB"pure_quanta_power"
ROOM"IO_SLOT"
HDL_POWER"GND";
"A"5;
%"Q_RES"
"2","(1775,3125)","0","pure_quanta","I50";
;
LOCATION"R718"
$SEC"1"
CDS_SEC"1"
PACK_TYPE"0402LF"
TOLERANCE"1%"
MATERIAL"CHIP"
WATTAGE"1/16W"
VALUE"1K"
CDS_LIB"pure_quanta"
PART_NUMBER"CS21002FB06";
"A"
$PN"1"25;
"B"
$PN"2"6;
%"UNIVERSAL_GND"
"1","(1775,2900)","0","pure_quanta_power","I51";
;
CDS_LIB"pure_quanta_power"
ROOM"IO_SLOT"
HDL_POWER"GND";
"A"6;
%"Q_RES"
"2","(1500,3125)","0","pure_quanta","I52";
;
LOCATION"R714"
$SEC"1"
CDS_SEC"1"
WATTAGE"1/16W"
VALUE"1K"
TOLERANCE"1%"
MATERIAL"CHIP"
PACK_TYPE"0402LF"
CDS_LIB"pure_quanta"
PART_NUMBER"CS21002FB06";
"A"
$PN"1"24;
"B"
$PN"2"7;
%"UNIVERSAL_GND"
"1","(1500,2900)","0","pure_quanta_power","I53";
;
CDS_LIB"pure_quanta_power"
ROOM"IO_SLOT"
HDL_POWER"GND";
"A"7;
%"UNIVERSAL_POWER"
"1","(-775,4025)","0","pure_quanta_power","I54";
;
HDL_POWER"P3V3_AUX"
CDS_LIB"pure_quanta_power";
"A"16;
%"Q_CAP"
"1","(-775,3700)","2","pure_quanta","I55";
;
LOCATION"C629"
$SEC"1"
CDS_SEC"1"
PACK_TYPE"0402"
VALUE"0.1UF"
VOLTAGE"25V"
TOLERANCE"10%"
MATERIAL"X7R"
CDS_LIB"pure_quanta"
PART_NUMBER"CH4104K1B00";
"B"
$PN"2"8;
"A"
$PN"1"16;
%"UNIVERSAL_GND"
"1","(-775,3475)","0","pure_quanta_power","I56";
;
CDS_LIB"pure_quanta_power"
HDL_POWER"GND";
"A"8;
%"Q_RES"
"2","(-1325,3075)","0","pure_quanta","I57";
;
LOCATION"R710"
$SEC"1"
CDS_SEC"1"
WATTAGE"1/16W"
PACK_TYPE"0402LF"
TOLERANCE"1%"
VALUE"1K"
MATERIAL"CHIP"
CDS_LIB"pure_quanta"
PART_NUMBER"CS21002FB06";
"A"
$PN"1"21;
"B"
$PN"2"9;
%"UNIVERSAL_GND"
"1","(-1325,2850)","0","pure_quanta_power","I58";
;
CDS_LIB"pure_quanta_power"
HDL_POWER"GND";
"A"9;
%"UNIVERSAL_GND"
"1","(200,3050)","0","pure_quanta_power","I59";
;
CDS_LIB"pure_quanta_power"
HDL_POWER"GND";
"A"15;
%"UNIVERSAL_POWER"
"1","(1500,4050)","0","pure_quanta_power","I60";
;
HDL_POWER"P3V3_AUX"
CDS_LIB"pure_quanta_power";
"A"14;
%"Q_RES"
"2","(2050,3125)","0","pure_quanta","I61";
;
LOCATION"R722"
$SEC"1"
CDS_SEC"1"
WATTAGE"1/16W"
MATERIAL"EMPTY"
PACK_TYPE"0402LF"
VALUE"1K"
TOLERANCE"1%"
CDS_LIB"pure_quanta"
PART_NUMBER"CS21002FB06";
"A"
$PN"1"23;
"B"
$PN"2"5;
%"Q_RES"
"2","(2050,3675)","0","pure_quanta","I62";
;
LOCATION"R721"
$SEC"1"
CDS_SEC"1"
VALUE"10K"
TOLERANCE"1%"
WATTAGE"1/16W"
MATERIAL"CHIP"
PACK_TYPE"0402LF"
CDS_LIB"pure_quanta"
PART_NUMBER"CS31002FB08";
"A"
$PN"1"14;
"B"
$PN"2"23;
%"Q_RES"
"2","(-1925,3650)","0","pure_quanta","I93";
;
LOCATION"R43"
$SEC"1"
CDS_SEC"1"
PACK_TYPE"0402LF"
VALUE"4.7K"
WATTAGE"1/16W"
TOLERANCE"5%"
MATERIAL"EMPTY"
CDS_LIB"pure_quanta"
PART_NUMBER"CS24702JB10";
"A"
$PN"1"11;
"B"
$PN"2"22;
%"Q_RES"
"2","(-2025,3650)","2","pure_quanta","I95";
;
LOCATION"R26"
$SEC"1"
CDS_SEC"1"
PACK_TYPE"0402LF"
WATTAGE"1/16W"
MATERIAL"EMPTY"
VALUE"4.7K"
TOLERANCE"5%"
CDS_LIB"pure_quanta"
PART_NUMBER"CS24702JB10";
"A"
$PN"1"11;
"B"
$PN"2"26;
%"UNIVERSAL_POWER"
"1","(-2025,3950)","0","pure_quanta_power","I96";
;
HDL_POWER"P3V3_AUX"
CDS_LIB"pure_quanta_power";
"A"11;
%"M24128BWMN6TP"
"1","(-225,1075)","0","pure_quanta","I97";
;
LOCATION"U1"
$SEC"1"
CDS_SEC"1"
MATERIAL"IC"
PART_TYPE"SMLF"
VALUE"M24128-BWMN6TP"
CDS_LIB"pure_quanta"
NEEDS_NO_SIZE"TRUE"
CDS_LMAN_SYM_OUTLINE"-150,125,150,-125"
PART_NUMBER"AKE30Z00613";
"E0"
$PN"1"20;
"E1"
$PN"2"12;
"E2"
$PN"3"28;
"VSS"
$PN"4"19;
"SDA"
$PN"5"27;
"SCL"
$PN"6"29;
"WC# \B"
$PN"7"31;
"VCC"
$PN"8"18;
%"UNIVERSAL_GND"
"1","(2075,600)","0","pure_quanta_power","I98";
;
ROOM"IO_SLOT"
CDS_LIB"pure_quanta_power"
HDL_POWER"GND";
"A"10;
END.
